# T6G (Grand Teton) — schematic netlist excerpt (pin names and nets, part order shuffled) for the footprints in the layout excerpt that follows; sources: Cadence DE-HDL packaged netlist, KiCad conversion of 04192023_DAF0TMB3IC0_F0TG_MB_C_brd_V02_OCP.brd

C6654  Q_CAP_DIFFBUS  DIFF BUS_0.22UF 6.3V 20% X6S  pkg C0201  page 319 : \1\ = P5E_CPU1_P0_TX_BUF_C_DN<12> ; \2\ = P5E_CPU1_P0_TX_BUF_DN<12>
R651  Q_RES  0 5% CHIP  pkg 0402LF  page 362 : A = P0V9_RETIMER_CPU0_EN ; B = P0V9_RETIMER_CPU0_EN0_R
R2669  Q_RES  2.2K 5% CHIP  pkg 0402LF  page 248 : A = P3V3_AUX ; B = SMB_BMC_SWB_BUF_R_SDA

(kicad_pcb
	(version 20260206)
	(generator "pcbnew")
	(generator_version "10.0")
	(general
		(thickness 1.6)
		(legacy_teardrops no)
	)
	(paper "A4")
	(title_block
		(title "04192023_DAF0TMB3IC0_F0TG_MB_C_brd_V02_OCP.brd")
		(comment 1 "Grand Teton / footprints 405-407 of 8354")
	)
	(layers
		(0 "F.Cu" signal "TOP")
		(4 "In1.Cu" signal "GND")
		(6 "In2.Cu" signal "IN1")
		(8 "In3.Cu" signal "GND1")
		(10 "In4.Cu" signal "IN2")
		(12 "In5.Cu" signal "GND2")
		(14 "In6.Cu" signal "IN3")
		(16 "In7.Cu" signal "GND3")
		(18 "In8.Cu" signal "VCC")
		(20 "In9.Cu" signal "VCC1")
		(22 "In10.Cu" signal "GND4")
		(24 "In11.Cu" signal "IN4")
		(26 "In12.Cu" signal "GND5")
		(28 "In13.Cu" signal "IN5")
		(30 "In14.Cu" signal "GND6")
		(32 "In15.Cu" signal "IN6")
		(34 "In16.Cu" signal "GND7")
		(2 "B.Cu" signal "BOTTOM")
		(9 "F.Adhes" user "F.Adhesive")
		(11 "B.Adhes" user "B.Adhesive")
		(13 "F.Paste" user "Package Geometry/Pastemask Top")
		(15 "B.Paste" user "Package Geometry/Pastemask Bottom")
		(5 "F.SilkS" user "Ref Des/Silkscreen Top")
		(7 "B.SilkS" user "Ref Des/Silkscreen Bottom")
		(1 "F.Mask" user "Board Geometry/Soldermask Top")
		(3 "B.Mask" user "Board Geometry/Soldermask Bottom")
		(17 "Dwgs.User" user "User.Drawings")
		(19 "Cmts.User" user "User.Comments")
		(21 "Eco1.User" user "User.Eco1")
		(23 "Eco2.User" user "User.Eco2")
		(25 "Edge.Cuts" user "Board Geometry/Outline")
		(27 "Margin" user)
		(31 "F.CrtYd" user "Package Geometry/Place Bound Top")
		(29 "B.CrtYd" user "Package Geometry/Place Bound Bottom")
		(35 "F.Fab" user "Ref Des/Assembly Top")
		(33 "B.Fab" user "Ref Des/Assembly Bottom")
	)
	(footprint ""
		(layer "F.Cu")
		(at 437.09463 -425.534836 90)
		(property "Reference" "R651"
			(at 0 0 90)
			(layer "F.SilkS")
			(hide yes)
			(effects
				(font
					(size 1.27 1.27)
				)
			)
		)
		(property "Value" ""
			(at 0 0 90)
			(layer "F.Fab")
			(effects
				(font
					(size 1.27 1.27)
				)
			)
		)
		(duplicate_pad_numbers_are_jumpers no)
		(fp_line
			(start 0.7874 -0.4064)
			(end 0.7874 0.4064)
			(stroke
				(width 0.1524)
				(type default)
			)
			(layer "F.SilkS")
		)
		(fp_line
			(start -0.7874 -0.4064)
			(end 0.7874 -0.4064)
			(stroke
				(width 0.1524)
				(type default)
			)
			(layer "F.SilkS")
		)
		(fp_line
			(start 0.7874 0.4064)
			(end -0.7874 0.4064)
			(stroke
				(width 0.1524)
				(type default)
			)
			(layer "F.SilkS")
		)
		(fp_line
			(start -0.7874 0.4064)
			(end -0.7874 -0.4064)
			(stroke
				(width 0.1524)
				(type default)
			)
			(layer "F.SilkS")
		)
		(fp_line
			(start -0.12065 -0.305054)
			(end -0.12065 -0.2794)
			(stroke
				(width 0.1)
				(type default)
			)
			(layer "F.Fab")
		)
		(fp_line
			(start -0.67945 -0.305054)
			(end -0.12065 -0.305054)
			(stroke
				(width 0.1)
				(type default)
			)
			(layer "F.Fab")
		)
		(fp_line
			(start 0.67945 -0.3048)
			(end 0.67945 0.3048)
			(stroke
				(width 0.1)
				(type default)
			)
			(layer "F.Fab")
		)
		(fp_line
			(start 0.12065 -0.3048)
			(end 0.67945 -0.3048)
			(stroke
				(width 0.1)
				(type default)
			)
			(layer "F.Fab")
		)
		(fp_line
			(start 0.12065 -0.2794)
			(end 0.12065 -0.3048)
			(stroke
				(width 0.1)
				(type default)
			)
			(layer "F.Fab")
		)
		(fp_line
			(start -0.12065 -0.2794)
			(end 0.12065 -0.2794)
			(stroke
				(width 0.1)
				(type default)
			)
			(layer "F.Fab")
		)
		(fp_line
			(start 0.120396 0.2794)
			(end -0.12065 0.2794)
			(stroke
				(width 0.1)
				(type default)
			)
			(layer "F.Fab")
		)
		(fp_line
			(start -0.12065 0.2794)
			(end -0.12065 0.3048)
			(stroke
				(width 0.1)
				(type default)
			)
			(layer "F.Fab")
		)
		(fp_line
			(start 0.67945 0.3048)
			(end 0.120396 0.3048)
			(stroke
				(width 0.1)
				(type default)
			)
			(layer "F.Fab")
		)
		(fp_line
			(start 0.120396 0.3048)
			(end 0.120396 0.2794)
			(stroke
				(width 0.1)
				(type default)
			)
			(layer "F.Fab")
		)
		(fp_line
			(start -0.12065 0.3048)
			(end -0.67945 0.3048)
			(stroke
				(width 0.1)
				(type default)
			)
			(layer "F.Fab")
		)
		(fp_line
			(start -0.67945 0.3048)
			(end -0.67945 -0.305054)
			(stroke
				(width 0.1)
				(type default)
			)
			(layer "F.Fab")
		)
		(pad "1" smd circle
			(at -0.40005 0 90)
			(size 0 0)
			(layers "F.Cu" "F.Mask" "F.Paste")
			(net "P0V9_RETIMER_CPU0_EN")
		)
		(pad "2" smd circle
			(at 0.40005 0 90)
			(size 0 0)
			(layers "F.Cu" "F.Mask" "F.Paste")
			(net "P0V9_RETIMER_CPU0_EN0_R")
		)
	)
	(footprint ""
		(layer "F.Cu")
		(at 84.527644 -408.517344 -90)
		(property "Reference" "C6654"
			(at 0 0 270)
			(layer "F.SilkS")
			(hide yes)
			(effects
				(font
					(size 1.27 1.27)
				)
			)
		)
		(property "Value" ""
			(at 0 0 270)
			(layer "F.Fab")
			(effects
				(font
					(size 1.27 1.27)
				)
			)
		)
		(duplicate_pad_numbers_are_jumpers no)
		(fp_line
			(start -0.299974 0.150114)
			(end -0.299974 -0.150114)
			(stroke
				(width 0.1)
				(type default)
			)
			(layer "F.Fab")
		)
		(fp_line
			(start 0.299974 0.150114)
			(end -0.299974 0.150114)
			(stroke
				(width 0.1)
				(type default)
			)
			(layer "F.Fab")
		)
		(fp_line
			(start -0.299974 -0.150114)
			(end 0.299974 -0.150114)
			(stroke
				(width 0.1)
				(type default)
			)
			(layer "F.Fab")
		)
		(fp_line
			(start 0.299974 -0.150114)
			(end 0.299974 0.150114)
			(stroke
				(width 0.1)
				(type default)
			)
			(layer "F.Fab")
		)
		(pad "1" smd rect
			(at -0.2667 0 270)
			(size 0.3048 0.381)
			(layers "F.Cu" "F.Mask" "F.Paste")
			(net "P5E_CPU1_P0_TX_BUF_C_DN<12>")
		)
		(pad "2" smd rect
			(at 0.2667 0 270)
			(size 0.3048 0.381)
			(layers "F.Cu" "F.Mask" "F.Paste")
			(net "P5E_CPU1_P0_TX_BUF_DN<12>")
		)
	)
	(footprint ""
		(layer "F.Cu")
		(at 168.656 -434.869336 180)
		(property "Reference" "R2669"
			(at 0 0 180)
			(layer "F.SilkS")
			(hide yes)
			(effects
				(font
					(size 1.27 1.27)
				)
			)
		)
		(property "Value" ""
			(at 0 0 180)
			(layer "F.Fab")
			(effects
				(font
					(size 1.27 1.27)
				)
			)
		)
		(duplicate_pad_numbers_are_jumpers no)
		(fp_line
			(start 0.7874 0.4064)
			(end -0.7874 0.4064)
			(stroke
				(width 0.1524)
				(type default)
			)
			(layer "F.SilkS")
		)
		(fp_line
			(start 0.7874 -0.4064)
			(end 0.7874 0.4064)
			(stroke
				(width 0.1524)
				(type default)
			)
			(layer "F.SilkS")
		)
		(fp_line
			(start -0.7874 0.4064)
			(end -0.7874 -0.4064)
			(stroke
				(width 0.1524)
				(type default)
			)
			(layer "F.SilkS")
		)
		(fp_line
			(start -0.7874 -0.4064)
			(end 0.7874 -0.4064)
			(stroke
				(width 0.1524)
				(type default)
			)
			(layer "F.SilkS")
		)
		(fp_line
			(start 0.67945 0.3048)
			(end 0.120396 0.3048)
			(stroke
				(width 0.1)
				(type default)
			)
			(layer "F.Fab")
		)
		(fp_line
			(start 0.67945 -0.3048)
			(end 0.67945 0.3048)
			(stroke
				(width 0.1)
				(type default)
			)
			(layer "F.Fab")
		)
		(fp_line
			(start 0.12065 -0.2794)
			(end 0.12065 -0.3048)
			(stroke
				(width 0.1)
				(type default)
			)
			(layer "F.Fab")
		)
		(fp_line
			(start 0.12065 -0.3048)
			(end 0.67945 -0.3048)
			(stroke
				(width 0.1)
				(type default)
			)
			(layer "F.Fab")
		)
		(fp_line
			(start 0.120396 0.3048)
			(end 0.120396 0.2794)
			(stroke
				(width 0.1)
				(type default)
			)
			(layer "F.Fab")
		)
		(fp_line
			(start 0.120396 0.2794)
			(end -0.12065 0.2794)
			(stroke
				(width 0.1)
				(type default)
			)
			(layer "F.Fab")
		)
		(fp_line
			(start -0.12065 0.3048)
			(end -0.67945 0.3048)
			(stroke
				(width 0.1)
				(type default)
			)
			(layer "F.Fab")
		)
		(fp_line
			(start -0.12065 0.2794)
			(end -0.12065 0.3048)
			(stroke
				(width 0.1)
				(type default)
			)
			(layer "F.Fab")
		)
		(fp_line
			(start -0.12065 -0.2794)
			(end 0.12065 -0.2794)
			(stroke
				(width 0.1)
				(type default)
			)
			(layer "F.Fab")
		)
		(fp_line
			(start -0.12065 -0.305054)
			(end -0.12065 -0.2794)
			(stroke
				(width 0.1)
				(type default)
			)
			(layer "F.Fab")
		)
		(fp_line
			(start -0.67945 0.3048)
			(end -0.67945 -0.305054)
			(stroke
				(width 0.1)
				(type default)
			)
			(layer "F.Fab")
		)
		(fp_line
			(start -0.67945 -0.305054)
			(end -0.12065 -0.305054)
			(stroke
				(width 0.1)
				(type default)
			)
			(layer "F.Fab")
		)
		(pad "1" smd circle
			(at -0.40005 0 180)
			(size 0 0)
			(layers "F.Cu" "F.Mask" "F.Paste")
			(net "P3V3_AUX")
		)
		(pad "2" smd circle
			(at 0.40005 0 180)
			(size 0 0)
			(layers "F.Cu" "F.Mask" "F.Paste")
			(net "SMB_BMC_SWB_BUF_R_SDA")
		)
	)
)
